(kicad_pcb
	(version 20260206)
	(generator "pcbnew")
	(generator_version "10.0")
	(general
		(thickness 1.6)
		(legacy_teardrops no)
	)
	(paper "A4")
	(title_block
		(title "01162023_DA0F0TEBIF0_F0T_Expander_BD_F_brd_V02_OCP.brd")
		(comment 1 "Grand Teton / footprints 7428-7434 of 9728")
	)
	(layers
		(0 "F.Cu" signal "TOP")
		(4 "In1.Cu" signal "GND")
		(6 "In2.Cu" signal "VCC")
		(8 "In3.Cu" signal "VCC1")
		(10 "In4.Cu" signal "GND1")
		(12 "In5.Cu" signal "IN1")
		(14 "In6.Cu" signal "GND2")
		(16 "In7.Cu" signal "IN2")
		(18 "In8.Cu" signal "GND3")
		(20 "In9.Cu" signal "IN3")
		(22 "In10.Cu" signal "GND4")
		(24 "In11.Cu" signal "IN4")
		(26 "In12.Cu" signal "GND5")
		(28 "In13.Cu" signal "IN5")
		(30 "In14.Cu" signal "GND6")
		(32 "In15.Cu" signal "IN6")
		(34 "In16.Cu" signal "GND7")
		(2 "B.Cu" signal "BOTTOM")
		(9 "F.Adhes" user "F.Adhesive")
		(11 "B.Adhes" user "B.Adhesive")
		(13 "F.Paste" user "Package Geometry/Pastemask Top")
		(15 "B.Paste" user "Package Geometry/Pastemask Bottom")
		(5 "F.SilkS" user "Ref Des/Silkscreen Top")
		(7 "B.SilkS" user "Ref Des/Silkscreen Bottom")
		(1 "F.Mask" user "Board Geometry/Soldermask Top")
		(3 "B.Mask" user "Board Geometry/Soldermask Bottom")
		(17 "Dwgs.User" user "User.Drawings")
		(19 "Cmts.User" user "User.Comments")
		(21 "Eco1.User" user "User.Eco1")
		(23 "Eco2.User" user "User.Eco2")
		(25 "Edge.Cuts" user "Board Geometry/Outline")
		(27 "Margin" user)
		(31 "F.CrtYd" user "Package Geometry/Place Bound Top")
		(29 "B.CrtYd" user "Package Geometry/Place Bound Bottom")
		(35 "F.Fab" user "Ref Des/Assembly Top")
		(33 "B.Fab" user "Ref Des/Assembly Bottom")
	)
	(footprint ""
		(layer "B.Cu")
		(at 234.724956 -272.889218)
		(property "Reference" "C4333"
			(at 0 0 0)
			(layer "B.SilkS")
			(hide yes)
			(effects
				(font
					(size 1.27 1.27)
				)
				(justify mirror)
			)
		)
		(property "Value" ""
			(at 0 0 0)
			(layer "B.Fab")
			(effects
				(font
					(size 1.27 1.27)
				)
				(justify mirror)
			)
		)
		(duplicate_pad_numbers_are_jumpers no)
		(fp_line
			(start -1.2954 -0.5842)
			(end -1.2954 0.5842)
			(stroke
				(width 0.1524)
				(type default)
			)
			(layer "B.SilkS")
		)
		(fp_line
			(start -1.2954 0.5842)
			(end 1.2954 0.5842)
			(stroke
				(width 0.1524)
				(type default)
			)
			(layer "B.SilkS")
		)
		(fp_line
			(start 1.2954 -0.5842)
			(end -1.2954 -0.5842)
			(stroke
				(width 0.1524)
				(type default)
			)
			(layer "B.SilkS")
		)
		(fp_line
			(start 1.2954 0.5842)
			(end 1.2954 -0.5842)
			(stroke
				(width 0.1524)
				(type default)
			)
			(layer "B.SilkS")
		)
		(fp_line
			(start -1.1938 -0.4064)
			(end -1.1938 0.4064)
			(stroke
				(width 0.1)
				(type default)
			)
			(layer "B.Fab")
		)
		(fp_line
			(start -1.1938 0.4064)
			(end -0.8636 0.4064)
			(stroke
				(width 0.1)
				(type default)
			)
			(layer "B.Fab")
		)
		(fp_line
			(start -0.8636 -0.4572)
			(end -0.8636 -0.4064)
			(stroke
				(width 0.1)
				(type default)
			)
			(layer "B.Fab")
		)
		(fp_line
			(start -0.8636 -0.4064)
			(end -1.1938 -0.4064)
			(stroke
				(width 0.1)
				(type default)
			)
			(layer "B.Fab")
		)
		(fp_line
			(start -0.8636 0.4064)
			(end -0.8636 0.4572)
			(stroke
				(width 0.1)
				(type default)
			)
			(layer "B.Fab")
		)
		(fp_line
			(start -0.8636 0.4572)
			(end 0.8636 0.4572)
			(stroke
				(width 0.1)
				(type default)
			)
			(layer "B.Fab")
		)
		(fp_line
			(start 0.8636 -0.4572)
			(end -0.8636 -0.4572)
			(stroke
				(width 0.1)
				(type default)
			)
			(layer "B.Fab")
		)
		(fp_line
			(start 0.8636 -0.4064)
			(end 0.8636 -0.4572)
			(stroke
				(width 0.1)
				(type default)
			)
			(layer "B.Fab")
		)
		(fp_line
			(start 0.8636 0.4064)
			(end 1.1938 0.4064)
			(stroke
				(width 0.1)
				(type default)
			)
			(layer "B.Fab")
		)
		(fp_line
			(start 0.8636 0.4572)
			(end 0.8636 0.4064)
			(stroke
				(width 0.1)
				(type default)
			)
			(layer "B.Fab")
		)
		(fp_line
			(start 1.1938 -0.4064)
			(end 0.8636 -0.4064)
			(stroke
				(width 0.1)
				(type default)
			)
			(layer "B.Fab")
		)
		(fp_line
			(start 1.1938 0.4064)
			(end 1.1938 -0.4064)
			(stroke
				(width 0.1)
				(type default)
			)
			(layer "B.Fab")
		)
		(pad "1" smd rect
			(at 0.7366 0 270)
			(size 0.7112 0.8128)
			(layers "B.Cu" "B.Mask" "B.Paste")
			(net "P1V25_PEX2")
		)
		(pad "2" smd rect
			(at -0.7366 0 270)
			(size 0.7112 0.8128)
			(layers "B.Cu" "B.Mask" "B.Paste")
			(net "GND")
		)
	)
	(footprint ""
		(layer "B.Cu")
		(at 217.700606 -273.94154)
		(property "Reference" "C4277"
			(at 0 0 0)
			(layer "B.SilkS")
			(hide yes)
			(effects
				(font
					(size 1.27 1.27)
				)
				(justify mirror)
			)
		)
		(property "Value" ""
			(at 0 0 0)
			(layer "B.Fab")
			(effects
				(font
					(size 1.27 1.27)
				)
				(justify mirror)
			)
		)
		(duplicate_pad_numbers_are_jumpers no)
		(fp_line
			(start -1.2954 -0.5842)
			(end -1.2954 0.5842)
			(stroke
				(width 0.1524)
				(type default)
			)
			(layer "B.SilkS")
		)
		(fp_line
			(start -1.2954 0.5842)
			(end 1.2954 0.5842)
			(stroke
				(width 0.1524)
				(type default)
			)
			(layer "B.SilkS")
		)
		(fp_line
			(start 1.2954 -0.5842)
			(end -1.2954 -0.5842)
			(stroke
				(width 0.1524)
				(type default)
			)
			(layer "B.SilkS")
		)
		(fp_line
			(start 1.2954 0.5842)
			(end 1.2954 -0.5842)
			(stroke
				(width 0.1524)
				(type default)
			)
			(layer "B.SilkS")
		)
		(fp_line
			(start -1.1938 -0.4064)
			(end -1.1938 0.4064)
			(stroke
				(width 0.1)
				(type default)
			)
			(layer "B.Fab")
		)
		(fp_line
			(start -1.1938 0.4064)
			(end -0.8636 0.4064)
			(stroke
				(width 0.1)
				(type default)
			)
			(layer "B.Fab")
		)
		(fp_line
			(start -0.8636 -0.4572)
			(end -0.8636 -0.4064)
			(stroke
				(width 0.1)
				(type default)
			)
			(layer "B.Fab")
		)
		(fp_line
			(start -0.8636 -0.4064)
			(end -1.1938 -0.4064)
			(stroke
				(width 0.1)
				(type default)
			)
			(layer "B.Fab")
		)
		(fp_line
			(start -0.8636 0.4064)
			(end -0.8636 0.4572)
			(stroke
				(width 0.1)
				(type default)
			)
			(layer "B.Fab")
		)
		(fp_line
			(start -0.8636 0.4572)
			(end 0.8636 0.4572)
			(stroke
				(width 0.1)
				(type default)
			)
			(layer "B.Fab")
		)
		(fp_line
			(start 0.8636 -0.4572)
			(end -0.8636 -0.4572)
			(stroke
				(width 0.1)
				(type default)
			)
			(layer "B.Fab")
		)
		(fp_line
			(start 0.8636 -0.4064)
			(end 0.8636 -0.4572)
			(stroke
				(width 0.1)
				(type default)
			)
			(layer "B.Fab")
		)
		(fp_line
			(start 0.8636 0.4064)
			(end 1.1938 0.4064)
			(stroke
				(width 0.1)
				(type default)
			)
			(layer "B.Fab")
		)
		(fp_line
			(start 0.8636 0.4572)
			(end 0.8636 0.4064)
			(stroke
				(width 0.1)
				(type default)
			)
			(layer "B.Fab")
		)
		(fp_line
			(start 1.1938 -0.4064)
			(end 0.8636 -0.4064)
			(stroke
				(width 0.1)
				(type default)
			)
			(layer "B.Fab")
		)
		(fp_line
			(start 1.1938 0.4064)
			(end 1.1938 -0.4064)
			(stroke
				(width 0.1)
				(type default)
			)
			(layer "B.Fab")
		)
		(pad "1" smd rect
			(at 0.7366 0 270)
			(size 0.7112 0.8128)
			(layers "B.Cu" "B.Mask" "B.Paste")
			(net "P1V25_PEX1")
		)
		(pad "2" smd rect
			(at -0.7366 0 270)
			(size 0.7112 0.8128)
			(layers "B.Cu" "B.Mask" "B.Paste")
			(net "GND")
		)
	)
	(footprint ""
		(layer "B.Cu")
		(at 209.384392 -234.033822)
		(property "Reference" "R6328"
			(at 0 0 0)
			(layer "B.SilkS")
			(hide yes)
			(effects
				(font
					(size 1.27 1.27)
				)
				(justify mirror)
			)
		)
		(property "Value" ""
			(at 0 0 0)
			(layer "B.Fab")
			(effects
				(font
					(size 1.27 1.27)
				)
				(justify mirror)
			)
		)
		(duplicate_pad_numbers_are_jumpers no)
		(fp_line
			(start -0.7874 -0.4064)
			(end -0.7874 0.4064)
			(stroke
				(width 0.1524)
				(type default)
			)
			(layer "B.SilkS")
		)
		(fp_line
			(start -0.7874 0.4064)
			(end 0.7874 0.4064)
			(stroke
				(width 0.1524)
				(type default)
			)
			(layer "B.SilkS")
		)
		(fp_line
			(start 0.7874 -0.4064)
			(end -0.7874 -0.4064)
			(stroke
				(width 0.1524)
				(type default)
			)
			(layer "B.SilkS")
		)
		(fp_line
			(start 0.7874 0.4064)
			(end 0.7874 -0.4064)
			(stroke
				(width 0.1524)
				(type default)
			)
			(layer "B.SilkS")
		)
		(fp_line
			(start -0.67945 -0.3048)
			(end -0.67945 0.3048)
			(stroke
				(width 0.1)
				(type default)
			)
			(layer "B.Fab")
		)
		(fp_line
			(start -0.67945 0.3048)
			(end -0.120396 0.3048)
			(stroke
				(width 0.1)
				(type default)
			)
			(layer "B.Fab")
		)
		(fp_line
			(start -0.12065 -0.3048)
			(end -0.67945 -0.3048)
			(stroke
				(width 0.1)
				(type default)
			)
			(layer "B.Fab")
		)
		(fp_line
			(start -0.12065 -0.2794)
			(end -0.12065 -0.3048)
			(stroke
				(width 0.1)
				(type default)
			)
			(layer "B.Fab")
		)
		(fp_line
			(start -0.120396 0.2794)
			(end 0.12065 0.2794)
			(stroke
				(width 0.1)
				(type default)
			)
			(layer "B.Fab")
		)
		(fp_line
			(start -0.120396 0.3048)
			(end -0.120396 0.2794)
			(stroke
				(width 0.1)
				(type default)
			)
			(layer "B.Fab")
		)
		(fp_line
			(start 0.12065 -0.305054)
			(end 0.12065 -0.2794)
			(stroke
				(width 0.1)
				(type default)
			)
			(layer "B.Fab")
		)
		(fp_line
			(start 0.12065 -0.2794)
			(end -0.12065 -0.2794)
			(stroke
				(width 0.1)
				(type default)
			)
			(layer "B.Fab")
		)
		(fp_line
			(start 0.12065 0.2794)
			(end 0.12065 0.3048)
			(stroke
				(width 0.1)
				(type default)
			)
			(layer "B.Fab")
		)
		(fp_line
			(start 0.12065 0.3048)
			(end 0.67945 0.3048)
			(stroke
				(width 0.1)
				(type default)
			)
			(layer "B.Fab")
		)
		(fp_line
			(start 0.67945 -0.305054)
			(end 0.12065 -0.305054)
			(stroke
				(width 0.1)
				(type default)
			)
			(layer "B.Fab")
		)
		(fp_line
			(start 0.67945 0.3048)
			(end 0.67945 -0.305054)
			(stroke
				(width 0.1)
				(type default)
			)
			(layer "B.Fab")
		)
		(pad "1" smd circle
			(at 0.40005 0 180)
			(size 0 0)
			(layers "B.Cu" "B.Mask" "B.Paste")
			(net "SMB_PEX2_SDA")
		)
		(pad "2" smd circle
			(at -0.40005 0 180)
			(size 0 0)
			(layers "B.Cu" "B.Mask" "B.Paste")
			(net "SMB_PEX2_MUX_SDA")
		)
	)
	(footprint ""
		(layer "B.Cu")
		(at 185.725054 -304.241454 90)
		(property "Reference" "C3186"
			(at 0 0 90)
			(layer "B.SilkS")
			(hide yes)
			(effects
				(font
					(size 1.27 1.27)
				)
				(justify mirror)
			)
		)
		(property "Value" ""
			(at 0 0 90)
			(layer "B.Fab")
			(effects
				(font
					(size 1.27 1.27)
				)
				(justify mirror)
			)
		)
		(duplicate_pad_numbers_are_jumpers no)
		(fp_line
			(start 0.299974 -0.150114)
			(end -0.299974 -0.150114)
			(stroke
				(width 0.1)
				(type default)
			)
			(layer "B.Fab")
		)
		(fp_line
			(start -0.299974 -0.150114)
			(end -0.299974 0.150114)
			(stroke
				(width 0.1)
				(type default)
			)
			(layer "B.Fab")
		)
		(fp_line
			(start 0.299974 0.150114)
			(end 0.299974 -0.150114)
			(stroke
				(width 0.1)
				(type default)
			)
			(layer "B.Fab")
		)
		(fp_line
			(start -0.299974 0.150114)
			(end 0.299974 0.150114)
			(stroke
				(width 0.1)
				(type default)
			)
			(layer "B.Fab")
		)
		(pad "1" smd rect
			(at 0.2667 0 270)
			(size 0.3048 0.381)
			(layers "B.Cu" "B.Mask" "B.Paste")
			(net "P1V8_VDDA_PEX1")
		)
		(pad "2" smd rect
			(at -0.2667 0 270)
			(size 0.3048 0.381)
			(layers "B.Cu" "B.Mask" "B.Paste")
			(net "GND")
		)
	)
	(footprint ""
		(layer "B.Cu")
		(at 117.097556 -308.580028 90)
		(property "Reference" "C1159"
			(at 0 0 90)
			(layer "B.SilkS")
			(hide yes)
			(effects
				(font
					(size 1.27 1.27)
				)
				(justify mirror)
			)
		)
		(property "Value" ""
			(at 0 0 90)
			(layer "B.Fab")
			(effects
				(font
					(size 1.27 1.27)
				)
				(justify mirror)
			)
		)
		(duplicate_pad_numbers_are_jumpers no)
		(fp_line
			(start 1.2954 -0.5842)
			(end -1.2954 -0.5842)
			(stroke
				(width 0.1524)
				(type default)
			)
			(layer "B.SilkS")
		)
		(fp_line
			(start -1.2954 -0.5842)
			(end -1.2954 0.5842)
			(stroke
				(width 0.1524)
				(type default)
			)
			(layer "B.SilkS")
		)
		(fp_line
			(start 1.2954 0.5842)
			(end 1.2954 -0.5842)
			(stroke
				(width 0.1524)
				(type default)
			)
			(layer "B.SilkS")
		)
		(fp_line
			(start -1.2954 0.5842)
			(end 1.2954 0.5842)
			(stroke
				(width 0.1524)
				(type default)
			)
			(layer "B.SilkS")
		)
		(fp_line
			(start 0.8636 -0.4572)
			(end -0.8636 -0.4572)
			(stroke
				(width 0.1)
				(type default)
			)
			(layer "B.Fab")
		)
		(fp_line
			(start -0.8636 -0.4572)
			(end -0.8636 -0.4064)
			(stroke
				(width 0.1)
				(type default)
			)
			(layer "B.Fab")
		)
		(fp_line
			(start 1.1938 -0.4064)
			(end 0.8636 -0.4064)
			(stroke
				(width 0.1)
				(type default)
			)
			(layer "B.Fab")
		)
		(fp_line
			(start 0.8636 -0.4064)
			(end 0.8636 -0.4572)
			(stroke
				(width 0.1)
				(type default)
			)
			(layer "B.Fab")
		)
		(fp_line
			(start -0.8636 -0.4064)
			(end -1.1938 -0.4064)
			(stroke
				(width 0.1)
				(type default)
			)
			(layer "B.Fab")
		)
		(fp_line
			(start -1.1938 -0.4064)
			(end -1.1938 0.4064)
			(stroke
				(width 0.1)
				(type default)
			)
			(layer "B.Fab")
		)
		(fp_line
			(start 1.1938 0.4064)
			(end 1.1938 -0.4064)
			(stroke
				(width 0.1)
				(type default)
			)
			(layer "B.Fab")
		)
		(fp_line
			(start 0.8636 0.4064)
			(end 1.1938 0.4064)
			(stroke
				(width 0.1)
				(type default)
			)
			(layer "B.Fab")
		)
		(fp_line
			(start -0.8636 0.4064)
			(end -0.8636 0.4572)
			(stroke
				(width 0.1)
				(type default)
			)
			(layer "B.Fab")
		)
		(fp_line
			(start -1.1938 0.4064)
			(end -0.8636 0.4064)
			(stroke
				(width 0.1)
				(type default)
			)
			(layer "B.Fab")
		)
		(fp_line
			(start 0.8636 0.4572)
			(end 0.8636 0.4064)
			(stroke
				(width 0.1)
				(type default)
			)
			(layer "B.Fab")
		)
		(fp_line
			(start -0.8636 0.4572)
			(end 0.8636 0.4572)
			(stroke
				(width 0.1)
				(type default)
			)
			(layer "B.Fab")
		)
		(pad "1" smd rect
			(at 0.7366 0)
			(size 0.7112 0.8128)
			(layers "B.Cu" "B.Mask" "B.Paste")
			(net "P0V8_SERDES_VDDA_PEX0")
		)
		(pad "2" smd rect
			(at -0.7366 0)
			(size 0.7112 0.8128)
			(layers "B.Cu" "B.Mask" "B.Paste")
			(net "GND")
		)
	)
	(footprint ""
		(layer "B.Cu")
		(at 212.09 -194.183 90)
		(property "Reference" "R1535"
			(at 0 0 90)
			(layer "B.SilkS")
			(hide yes)
			(effects
				(font
					(size 1.27 1.27)
				)
				(justify mirror)
			)
		)
		(property "Value" ""
			(at 0 0 90)
			(layer "B.Fab")
			(effects
				(font
					(size 1.27 1.27)
				)
				(justify mirror)
			)
		)
		(duplicate_pad_numbers_are_jumpers no)
		(fp_line
			(start 0.7874 -0.4064)
			(end -0.7874 -0.4064)
			(stroke
				(width 0.1524)
				(type default)
			)
			(layer "B.SilkS")
		)
		(fp_line
			(start -0.7874 -0.4064)
			(end -0.7874 0.4064)
			(stroke
				(width 0.1524)
				(type default)
			)
			(layer "B.SilkS")
		)
		(fp_line
			(start 0.7874 0.4064)
			(end 0.7874 -0.4064)
			(stroke
				(width 0.1524)
				(type default)
			)
			(layer "B.SilkS")
		)
		(fp_line
			(start -0.7874 0.4064)
			(end 0.7874 0.4064)
			(stroke
				(width 0.1524)
				(type default)
			)
			(layer "B.SilkS")
		)
		(fp_line
			(start 0.67945 -0.305054)
			(end 0.12065 -0.305054)
			(stroke
				(width 0.1)
				(type default)
			)
			(layer "B.Fab")
		)
		(fp_line
			(start 0.12065 -0.305054)
			(end 0.12065 -0.2794)
			(stroke
				(width 0.1)
				(type default)
			)
			(layer "B.Fab")
		)
		(fp_line
			(start -0.12065 -0.3048)
			(end -0.67945 -0.3048)
			(stroke
				(width 0.1)
				(type default)
			)
			(layer "B.Fab")
		)
		(fp_line
			(start -0.67945 -0.3048)
			(end -0.67945 0.3048)
			(stroke
				(width 0.1)
				(type default)
			)
			(layer "B.Fab")
		)
		(fp_line
			(start 0.12065 -0.2794)
			(end -0.12065 -0.2794)
			(stroke
				(width 0.1)
				(type default)
			)
			(layer "B.Fab")
		)
		(fp_line
			(start -0.12065 -0.2794)
			(end -0.12065 -0.3048)
			(stroke
				(width 0.1)
				(type default)
			)
			(layer "B.Fab")
		)
		(fp_line
			(start 0.12065 0.2794)
			(end 0.12065 0.3048)
			(stroke
				(width 0.1)
				(type default)
			)
			(layer "B.Fab")
		)
		(fp_line
			(start -0.120396 0.2794)
			(end 0.12065 0.2794)
			(stroke
				(width 0.1)
				(type default)
			)
			(layer "B.Fab")
		)
		(fp_line
			(start 0.67945 0.3048)
			(end 0.67945 -0.305054)
			(stroke
				(width 0.1)
				(type default)
			)
			(layer "B.Fab")
		)
		(fp_line
			(start 0.12065 0.3048)
			(end 0.67945 0.3048)
			(stroke
				(width 0.1)
				(type default)
			)
			(layer "B.Fab")
		)
		(fp_line
			(start -0.120396 0.3048)
			(end -0.120396 0.2794)
			(stroke
				(width 0.1)
				(type default)
			)
			(layer "B.Fab")
		)
		(fp_line
			(start -0.67945 0.3048)
			(end -0.120396 0.3048)
			(stroke
				(width 0.1)
				(type default)
			)
			(layer "B.Fab")
		)
		(pad "1" smd circle
			(at 0.40005 0 270)
			(size 0 0)
			(layers "B.Cu" "B.Mask" "B.Paste")
			(net "SMB_NIC7_LS_R_SDA")
		)
		(pad "2" smd circle
			(at -0.40005 0 270)
			(size 0 0)
			(layers "B.Cu" "B.Mask" "B.Paste")
			(net "SMB_NIC7_R_SDA")
		)
	)
	(footprint ""
		(layer "B.Cu")
		(at 48.72482 -293.99992 90)
		(property "Reference" "C1108"
			(at 0 0 90)
			(layer "B.SilkS")
			(hide yes)
			(effects
				(font
					(size 1.27 1.27)
				)
				(justify mirror)
			)
		)
		(property "Value" ""
			(at 0 0 90)
			(layer "B.Fab")
			(effects
				(font
					(size 1.27 1.27)
				)
				(justify mirror)
			)
		)
		(duplicate_pad_numbers_are_jumpers no)
		(fp_line
			(start 0.299974 -0.150114)
			(end -0.299974 -0.150114)
			(stroke
				(width 0.1)
				(type default)
			)
			(layer "B.Fab")
		)
		(fp_line
			(start -0.299974 -0.150114)
			(end -0.299974 0.150114)
			(stroke
				(width 0.1)
				(type default)
			)
			(layer "B.Fab")
		)
		(fp_line
			(start 0.299974 0.150114)
			(end 0.299974 -0.150114)
			(stroke
				(width 0.1)
				(type default)
			)
			(layer "B.Fab")
		)
		(fp_line
			(start -0.299974 0.150114)
			(end 0.299974 0.150114)
			(stroke
				(width 0.1)
				(type default)
			)
			(layer "B.Fab")
		)
		(pad "1" smd rect
			(at 0.2667 0 270)
			(size 0.3048 0.381)
			(layers "B.Cu" "B.Mask" "B.Paste")
			(net "P0V8_PEX0")
		)
		(pad "2" smd rect
			(at -0.2667 0 270)
			(size 0.3048 0.381)
			(layers "B.Cu" "B.Mask" "B.Paste")
			(net "GND")
		)
	)
)
